(kicad_pcb
	(version 20260206)
	(generator "pcbnew")
	(generator_version "10.0")
	(general
		(thickness 1.6)
		(legacy_teardrops no)
	)
	(paper "A4")
	(title_block
		(title "Wiwynn_Tioga_Pass_MB.brd")
		(comment 1 "Tioga Pass / footprints 674-680 of 4770")
	)
	(layers
		(0 "F.Cu" signal "TOP")
		(4 "In1.Cu" signal "L2GND")
		(6 "In2.Cu" signal "L3")
		(8 "In3.Cu" signal "L4GND")
		(10 "In4.Cu" signal "L5")
		(12 "In5.Cu" signal "L6GND")
		(14 "In6.Cu" signal "L7VCC")
		(16 "In7.Cu" signal "L8VCC")
		(18 "In8.Cu" signal "L9GND")
		(20 "In9.Cu" signal "L10")
		(22 "In10.Cu" signal "L11GND")
		(24 "In11.Cu" signal "L12")
		(26 "In12.Cu" signal "L13GND")
		(2 "B.Cu" signal "BOTTOM")
		(9 "F.Adhes" user "F.Adhesive")
		(11 "B.Adhes" user "B.Adhesive")
		(13 "F.Paste" user "Package Geometry/Pastemask Top")
		(15 "B.Paste" user "Package Geometry/Pastemask Bottom")
		(5 "F.SilkS" user "Ref Des/Silkscreen Top")
		(7 "B.SilkS" user "Ref Des/Silkscreen Bottom")
		(1 "F.Mask" user "Board Geometry/Soldermask Top")
		(3 "B.Mask" user "Board Geometry/Soldermask Bottom")
		(17 "Dwgs.User" user "User.Drawings")
		(19 "Cmts.User" user "User.Comments")
		(21 "Eco1.User" user "User.Eco1")
		(23 "Eco2.User" user "User.Eco2")
		(25 "Edge.Cuts" user "Board Geometry/Outline")
		(27 "Margin" user)
		(31 "F.CrtYd" user "Package Geometry/Place Bound Top")
		(29 "B.CrtYd" user "Package Geometry/Place Bound Bottom")
		(35 "F.Fab" user "Ref Des/Assembly Top")
		(33 "B.Fab" user "Ref Des/Assembly Bottom")
	)
	(footprint ""
		(layer "F.Cu")
		(at 13.8938 -25.908 90)
		(property "Reference" "C1F16"
			(at 0 0 90)
			(layer "F.SilkS")
			(hide yes)
			(effects
				(font
					(size 1.27 1.27)
				)
			)
		)
		(property "Value" ""
			(at 0 0 90)
			(layer "F.Fab")
			(effects
				(font
					(size 1.27 1.27)
				)
			)
		)
		(duplicate_pad_numbers_are_jumpers no)
		(fp_rect
			(start -0.3048 -0.1016)
			(end 0.3048 0.9906)
			(stroke
				(width 0)
				(type default)
			)
			(fill no)
			(layer "F.CrtYd")
		)
		(fp_line
			(start 0.3048 -0.1016)
			(end -0.3048 -0.1016)
			(stroke
				(width 0.1)
				(type default)
			)
			(layer "F.Fab")
		)
		(fp_line
			(start -0.3048 -0.1016)
			(end -0.3048 0.9906)
			(stroke
				(width 0.1)
				(type default)
			)
			(layer "F.Fab")
		)
		(fp_line
			(start 0.3048 0.9906)
			(end 0.3048 -0.1016)
			(stroke
				(width 0.1)
				(type default)
			)
			(layer "F.Fab")
		)
		(fp_line
			(start -0.3048 0.9906)
			(end 0.3048 0.9906)
			(stroke
				(width 0.1)
				(type default)
			)
			(layer "F.Fab")
		)
		(pad "1" smd rect
			(at 0 0 90)
			(size 0.508 0.508)
			(layers "F.Cu" "F.Mask" "F.Paste")
			(net "P3E_CPU1_PE3_MP_C_TXN<1>")
		)
		(pad "2" smd rect
			(at 0 0.889 90)
			(size 0.508 0.508)
			(layers "F.Cu" "F.Mask" "F.Paste")
			(net "P3E_CPU1_PE3_MP_TXN<1>")
		)
		(zone
			(layer "F.Cu")
			(hatch none 0.5)
			(connect_pads
				(clearance 0)
			)
			(min_thickness 0.25)
			(keepout
				(tracks not_allowed)
				(vias allowed)
				(pads allowed)
				(copperpour not_allowed)
				(footprints allowed)
			)
			(placement
				(enabled no)
				(sheetname "")
			)
			(fill
				(thermal_gap 0.5)
				(thermal_bridge_width 0.5)
				(island_removal_mode 0)
			)
			(polygon
				(pts
					(xy 14.1478 -25.654) (xy 14.5288 -25.654) (xy 14.5288 -26.162) (xy 14.1478 -26.162)
				)
			)
		)
		(zone
			(layer "F.Cu")
			(hatch none 0.5)
			(connect_pads
				(clearance 0)
			)
			(min_thickness 0.25)
			(keepout
				(tracks allowed)
				(vias not_allowed)
				(pads allowed)
				(copperpour not_allowed)
				(footprints allowed)
			)
			(placement
				(enabled no)
				(sheetname "")
			)
			(fill
				(thermal_gap 0.5)
				(thermal_bridge_width 0.5)
				(island_removal_mode 0)
			)
			(polygon
				(pts
					(xy 14.1478 -25.654) (xy 14.5288 -25.654) (xy 14.5288 -26.162) (xy 14.1478 -26.162)
				)
			)
		)
	)
	(footprint ""
		(layer "F.Cu")
		(at 339.9282 -128.3335)
		(property "Reference" "C7B11"
			(at 0 0 0)
			(layer "F.SilkS")
			(hide yes)
			(effects
				(font
					(size 1.27 1.27)
				)
			)
		)
		(property "Value" ""
			(at 0 0 0)
			(layer "F.Fab")
			(effects
				(font
					(size 1.27 1.27)
				)
			)
		)
		(duplicate_pad_numbers_are_jumpers no)
		(fp_poly
			(pts
				(xy 0.3048 -0.1016) (xy 0.3048 0.9906) (xy -0.3048 0.9906) (xy -0.3048 -0.1016)
			)
			(stroke
				(width 0)
				(type default)
			)
			(fill no)
			(layer "F.CrtYd")
		)
		(fp_line
			(start -0.3048 -0.1016)
			(end -0.3048 0.9906)
			(stroke
				(width 0.1)
				(type default)
			)
			(layer "F.Fab")
		)
		(fp_line
			(start -0.3048 0.9906)
			(end 0.3048 0.9906)
			(stroke
				(width 0.1)
				(type default)
			)
			(layer "F.Fab")
		)
		(fp_line
			(start 0.3048 -0.1016)
			(end -0.3048 -0.1016)
			(stroke
				(width 0.1)
				(type default)
			)
			(layer "F.Fab")
		)
		(fp_line
			(start 0.3048 0.9906)
			(end 0.3048 -0.1016)
			(stroke
				(width 0.1)
				(type default)
			)
			(layer "F.Fab")
		)
		(pad "1" smd rect
			(at 0 0)
			(size 0.508 0.508)
			(layers "F.Cu" "F.Mask" "F.Paste")
			(net "VR_PVPP_DEF_SS")
		)
		(pad "2" smd rect
			(at 0 0.889)
			(size 0.508 0.508)
			(layers "F.Cu" "F.Mask" "F.Paste")
			(net "AGND_PVPP_DEF")
		)
		(zone
			(layer "F.Cu")
			(hatch none 0.5)
			(connect_pads
				(clearance 0)
			)
			(min_thickness 0.25)
			(keepout
				(tracks allowed)
				(vias not_allowed)
				(pads allowed)
				(copperpour not_allowed)
				(footprints allowed)
			)
			(placement
				(enabled no)
				(sheetname "")
			)
			(fill
				(thermal_gap 0.5)
				(thermal_bridge_width 0.5)
				(island_removal_mode 0)
			)
			(polygon
				(pts
					(xy 339.6742 -128.0795) (xy 340.1822 -128.0795) (xy 340.1822 -127.6985) (xy 339.6742 -127.6985)
				)
			)
		)
		(zone
			(layer "F.Cu")
			(hatch none 0.5)
			(connect_pads
				(clearance 0)
			)
			(min_thickness 0.25)
			(keepout
				(tracks not_allowed)
				(vias allowed)
				(pads allowed)
				(copperpour not_allowed)
				(footprints allowed)
			)
			(placement
				(enabled no)
				(sheetname "")
			)
			(fill
				(thermal_gap 0.5)
				(thermal_bridge_width 0.5)
				(island_removal_mode 0)
			)
			(polygon
				(pts
					(xy 339.6742 -127.6985) (xy 340.1822 -127.6985) (xy 340.1822 -128.0795) (xy 339.6742 -128.0795)
				)
			)
		)
	)
	(footprint ""
		(layer "F.Cu")
		(at 349.1738 -157.2768 90)
		(property "Reference" "C7A16"
			(at 0 0 90)
			(layer "F.SilkS")
			(hide yes)
			(effects
				(font
					(size 1.27 1.27)
				)
			)
		)
		(property "Value" ""
			(at 0 0 90)
			(layer "F.Fab")
			(effects
				(font
					(size 1.27 1.27)
				)
			)
		)
		(duplicate_pad_numbers_are_jumpers no)
		(fp_poly
			(pts
				(xy 0.3048 -0.1016) (xy 0.3048 0.9906) (xy -0.3048 0.9906) (xy -0.3048 -0.1016)
			)
			(stroke
				(width 0)
				(type default)
			)
			(fill no)
			(layer "F.CrtYd")
		)
		(fp_line
			(start 0.3048 -0.1016)
			(end -0.3048 -0.1016)
			(stroke
				(width 0.1)
				(type default)
			)
			(layer "F.Fab")
		)
		(fp_line
			(start -0.3048 -0.1016)
			(end -0.3048 0.9906)
			(stroke
				(width 0.1)
				(type default)
			)
			(layer "F.Fab")
		)
		(fp_line
			(start 0.3048 0.9906)
			(end 0.3048 -0.1016)
			(stroke
				(width 0.1)
				(type default)
			)
			(layer "F.Fab")
		)
		(fp_line
			(start -0.3048 0.9906)
			(end 0.3048 0.9906)
			(stroke
				(width 0.1)
				(type default)
			)
			(layer "F.Fab")
		)
		(pad "1" smd rect
			(at 0 0 90)
			(size 0.508 0.508)
			(layers "F.Cu" "F.Mask" "F.Paste")
			(net "VR_PVDDQ_DEF_PH1_VCIN")
		)
		(pad "2" smd rect
			(at 0 0.889 90)
			(size 0.508 0.508)
			(layers "F.Cu" "F.Mask" "F.Paste")
			(net "GND")
		)
		(zone
			(layer "F.Cu")
			(hatch none 0.5)
			(connect_pads
				(clearance 0)
			)
			(min_thickness 0.25)
			(keepout
				(tracks allowed)
				(vias not_allowed)
				(pads allowed)
				(copperpour not_allowed)
				(footprints allowed)
			)
			(placement
				(enabled no)
				(sheetname "")
			)
			(fill
				(thermal_gap 0.5)
				(thermal_bridge_width 0.5)
				(island_removal_mode 0)
			)
			(polygon
				(pts
					(xy 349.4278 -157.0228) (xy 349.4278 -157.5308) (xy 349.8088 -157.5308) (xy 349.8088 -157.0228)
				)
			)
		)
		(zone
			(layer "F.Cu")
			(hatch none 0.5)
			(connect_pads
				(clearance 0)
			)
			(min_thickness 0.25)
			(keepout
				(tracks not_allowed)
				(vias allowed)
				(pads allowed)
				(copperpour not_allowed)
				(footprints allowed)
			)
			(placement
				(enabled no)
				(sheetname "")
			)
			(fill
				(thermal_gap 0.5)
				(thermal_bridge_width 0.5)
				(island_removal_mode 0)
			)
			(polygon
				(pts
					(xy 349.8088 -157.0228) (xy 349.8088 -157.5308) (xy 349.4278 -157.5308) (xy 349.4278 -157.0228)
				)
			)
		)
	)
	(footprint ""
		(layer "F.Cu")
		(at 388.502906 -164.916612 90)
		(property "Reference" "T1D20"
			(at 0 0 90)
			(layer "F.SilkS")
			(hide yes)
			(effects
				(font
					(size 1.27 1.27)
				)
			)
		)
		(property "Value" "*"
			(at -3.4036 -4.46405 90)
			(unlocked yes)
			(layer "F.Fab")
			(hide yes)
			(effects
				(font
					(size 0.889 0.889)
					(thickness 0.1524)
				)
			)
		)
		(property "Device Type" "TEST-PAD-12P-1-GP-U_DISCRET-GBA"
			(at -3.4036 -5.98805 90)
			(unlocked yes)
			(layer "F.Fab")
			(hide yes)
			(effects
				(font
					(size 0.889 0.889)
					(thickness 0.1524)
				)
			)
		)
		(duplicate_pad_numbers_are_jumpers no)
		(fp_line
			(start 2.3622 -4.826)
			(end 2.3622 3.4798)
			(stroke
				(width 0.1524)
				(type default)
			)
			(layer "F.SilkS")
		)
		(fp_line
			(start -2.3876 -4.826)
			(end 2.3622 -4.826)
			(stroke
				(width 0.1524)
				(type default)
			)
			(layer "F.SilkS")
		)
		(fp_line
			(start 2.3622 3.4798)
			(end -2.3876 3.4798)
			(stroke
				(width 0.1524)
				(type default)
			)
			(layer "F.SilkS")
		)
		(fp_line
			(start -2.3876 3.4798)
			(end -2.3876 -4.826)
			(stroke
				(width 0.1524)
				(type default)
			)
			(layer "F.SilkS")
		)
		(fp_rect
			(start -2.6416 3.7338)
			(end 2.6162 -5.08)
			(stroke
				(width 0)
				(type default)
			)
			(fill no)
			(layer "F.CrtYd")
		)
		(fp_rect
			(start -2.6416 3.7338)
			(end 2.6162 -5.08)
			(stroke
				(width 0)
				(type default)
			)
			(fill no)
			(layer "F.Fab")
		)
		(pad "1" smd circle
			(at 0.496824 -1.301496 90)
			(size 0.6604 0.6604)
			(layers "F.Cu" "F.Mask" "F.Paste")
			(net "L10_85OHM_10INCH_DN")
		)
		(pad "2" smd circle
			(at -0.503936 -1.301496 90)
			(size 0.6604 0.6604)
			(layers "F.Cu" "F.Mask" "F.Paste")
			(net "L10_85OHM_10INCH_DP")
		)
		(pad "3" smd custom
			(at -0.00889 0.370078 90)
			(size 0.74295 0.74295)
			(layers "F.Cu" "F.Mask" "F.Paste")
			(net "GND")
			(options
				(clearance outline)
				(anchor circle)
			)
			(primitives
				(gr_poly
					(pts
						(xy -2.1209 1.4859) (xy 2.1209 1.4859) (xy 2.1209 -1.4859) (xy 1.08585 -1.4859) (xy 1.08585 -0.4699)
						(xy -1.08585 -0.4699) (xy -1.08585 -1.4859) (xy -2.1209 -1.4859)
					)
					(width 0)
					(fill yes)
				)
			)
		)
		(pad "4" thru_hole circle
			(at 1.266444 -3.851656 90)
			(size 1.4478 1.4478)
			(drill 1.0414)
			(layers "*.Cu" "*.Mask")
			(remove_unused_layers no)
			(net "GND")
			(clearance 0.1524)
			(thermal_gap 0.1524)
		)
		(pad "5" thru_hole circle
			(at -1.273556 -3.851656 90)
			(size 1.4478 1.4478)
			(drill 1.0414)
			(layers "*.Cu" "*.Mask")
			(remove_unused_layers no)
			(net "GND")
			(clearance 0.1524)
			(thermal_gap 0.1524)
		)
		(pad "6" thru_hole circle
			(at 1.266444 2.498344 90)
			(size 1.4478 1.4478)
			(drill 1.0414)
			(layers "*.Cu" "*.Mask")
			(remove_unused_layers no)
			(net "GND")
			(clearance 0.1524)
			(thermal_gap 0.1524)
		)
		(pad "7" thru_hole circle
			(at -1.273556 2.498344 90)
			(size 1.4478 1.4478)
			(drill 1.0414)
			(layers "*.Cu" "*.Mask")
			(remove_unused_layers no)
			(net "GND")
			(clearance 0.1524)
			(thermal_gap 0.1524)
		)
		(pad "8" thru_hole circle
			(at 1.27 -0.4572 90)
			(size 0.7112 0.7112)
			(drill 0.4064)
			(layers "*.Cu" "*.Mask")
			(remove_unused_layers no)
			(net "GND")
			(clearance 0.1016)
			(thermal_gap 0.1016)
		)
		(pad "9" thru_hole circle
			(at 1.27 0.762 90)
			(size 0.7112 0.7112)
			(drill 0.4064)
			(layers "*.Cu" "*.Mask")
			(remove_unused_layers no)
			(net "GND")
			(clearance 0.1016)
			(thermal_gap 0.1016)
		)
		(pad "10" thru_hole circle
			(at -0.0254 0.762 90)
			(size 0.7112 0.7112)
			(drill 0.4064)
			(layers "*.Cu" "*.Mask")
			(remove_unused_layers no)
			(net "GND")
			(clearance 0.1016)
			(thermal_gap 0.1016)
		)
		(pad "11" thru_hole circle
			(at -1.27 0.762 90)
			(size 0.7112 0.7112)
			(drill 0.4064)
			(layers "*.Cu" "*.Mask")
			(remove_unused_layers no)
			(net "GND")
			(clearance 0.1016)
			(thermal_gap 0.1016)
		)
		(pad "12" thru_hole circle
			(at -1.27 -0.4572 90)
			(size 0.7112 0.7112)
			(drill 0.4064)
			(layers "*.Cu" "*.Mask")
			(remove_unused_layers no)
			(net "GND")
			(clearance 0.1016)
			(thermal_gap 0.1016)
		)
	)
	(footprint ""
		(layer "F.Cu")
		(at 153.5176 -130.3528 -90)
		(property "Reference" "C3B1"
			(at 0 0 270)
			(layer "F.SilkS")
			(hide yes)
			(effects
				(font
					(size 1.27 1.27)
				)
			)
		)
		(property "Value" ""
			(at 0 0 270)
			(layer "F.Fab")
			(effects
				(font
					(size 1.27 1.27)
				)
			)
		)
		(duplicate_pad_numbers_are_jumpers no)
		(fp_rect
			(start -0.4953 1.6002)
			(end 0.4953 -0.2032)
			(stroke
				(width 0)
				(type default)
			)
			(fill no)
			(layer "F.CrtYd")
		)
		(fp_line
			(start -0.4953 1.6002)
			(end -0.4953 -0.2032)
			(stroke
				(width 0.1)
				(type default)
			)
			(layer "F.Fab")
		)
		(fp_line
			(start 0.4953 1.6002)
			(end -0.4953 1.6002)
			(stroke
				(width 0.1)
				(type default)
			)
			(layer "F.Fab")
		)
		(fp_line
			(start -0.4953 -0.2032)
			(end 0.4953 -0.2032)
			(stroke
				(width 0.1)
				(type default)
			)
			(layer "F.Fab")
		)
		(fp_line
			(start 0.4953 -0.2032)
			(end 0.4953 1.6002)
			(stroke
				(width 0.1)
				(type default)
			)
			(layer "F.Fab")
		)
		(pad "1" smd rect
			(at 0 0 270)
			(size 0.762 0.889)
			(layers "F.Cu" "F.Mask" "F.Paste")
			(net "PVPP_KLM")
		)
		(pad "2" smd rect
			(at 0 1.397 270)
			(size 0.762 0.889)
			(layers "F.Cu" "F.Mask" "F.Paste")
			(net "GND")
		)
		(zone
			(layer "F.Cu")
			(hatch none 0.5)
			(connect_pads
				(clearance 0)
			)
			(min_thickness 0.25)
			(keepout
				(tracks not_allowed)
				(vias allowed)
				(pads allowed)
				(copperpour not_allowed)
				(footprints allowed)
			)
			(placement
				(enabled no)
				(sheetname "")
			)
			(fill
				(thermal_gap 0.5)
				(thermal_bridge_width 0.5)
				(island_removal_mode 0)
			)
			(polygon
				(pts
					(xy 152.5651 -130.7338) (xy 152.5651 -129.9718) (xy 153.0731 -129.9718) (xy 153.0731 -130.7338)
				)
			)
		)
	)
	(footprint ""
		(layer "F.Cu")
		(at 193.9036 -75.1332 90)
		(property "Reference" "C4D28"
			(at 0 0 90)
			(layer "F.SilkS")
			(hide yes)
			(effects
				(font
					(size 1.27 1.27)
				)
			)
		)
		(property "Value" ""
			(at 0 0 90)
			(layer "F.Fab")
			(effects
				(font
					(size 1.27 1.27)
				)
			)
		)
		(duplicate_pad_numbers_are_jumpers no)
		(fp_rect
			(start -0.3048 0.9906)
			(end 0.3048 -0.1016)
			(stroke
				(width 0)
				(type default)
			)
			(fill no)
			(layer "F.CrtYd")
		)
		(fp_line
			(start 0.3048 -0.1016)
			(end -0.3048 -0.1016)
			(stroke
				(width 0.1)
				(type default)
			)
			(layer "F.Fab")
		)
		(fp_line
			(start -0.3048 -0.1016)
			(end -0.3048 0.9906)
			(stroke
				(width 0.1)
				(type default)
			)
			(layer "F.Fab")
		)
		(fp_line
			(start 0.3048 0.9906)
			(end 0.3048 -0.1016)
			(stroke
				(width 0.1)
				(type default)
			)
			(layer "F.Fab")
		)
		(fp_line
			(start -0.3048 0.9906)
			(end 0.3048 0.9906)
			(stroke
				(width 0.1)
				(type default)
			)
			(layer "F.Fab")
		)
		(pad "1" smd rect
			(at 0 0 90)
			(size 0.508 0.508)
			(layers "F.Cu" "F.Mask" "F.Paste")
			(net "VR_PVCCIN_CPU0_PH3_BOOT")
		)
		(pad "2" smd rect
			(at 0 0.889 90)
			(size 0.508 0.508)
			(layers "F.Cu" "F.Mask" "F.Paste")
			(net "VR_PVCCIN_CPU0_PH3_PHASE")
		)
		(zone
			(layer "F.Cu")
			(hatch none 0.5)
			(connect_pads
				(clearance 0)
			)
			(min_thickness 0.25)
			(keepout
				(tracks allowed)
				(vias not_allowed)
				(pads allowed)
				(copperpour not_allowed)
				(footprints allowed)
			)
			(placement
				(enabled no)
				(sheetname "")
			)
			(fill
				(thermal_gap 0.5)
				(thermal_bridge_width 0.5)
				(island_removal_mode 0)
			)
			(polygon
				(pts
					(xy 194.5386 -74.8792) (xy 194.5386 -75.3872) (xy 194.1576 -75.3872) (xy 194.1576 -74.8792)
				)
			)
		)
		(zone
			(layer "F.Cu")
			(hatch none 0.5)
			(connect_pads
				(clearance 0)
			)
			(min_thickness 0.25)
			(keepout
				(tracks not_allowed)
				(vias allowed)
				(pads allowed)
				(copperpour not_allowed)
				(footprints allowed)
			)
			(placement
				(enabled no)
				(sheetname "")
			)
			(fill
				(thermal_gap 0.5)
				(thermal_bridge_width 0.5)
				(island_removal_mode 0)
			)
			(polygon
				(pts
					(xy 194.5386 -74.8792) (xy 194.5386 -75.3872) (xy 194.1576 -75.3872) (xy 194.1576 -74.8792)
				)
			)
		)
	)
	(footprint ""
		(layer "F.Cu")
		(at 163.449 -47.879 90)
		(property "Reference" "C4E29"
			(at 2.92862 3.24612 0)
			(unlocked yes)
			(layer "F.SilkS")
			(effects
				(font
					(size 0.4064 0.254)
					(thickness 0.1524)
				)
			)
		)
		(property "Value" ""
			(at 0 0 90)
			(layer "F.Fab")
			(effects
				(font
					(size 1.27 1.27)
				)
			)
		)
		(duplicate_pad_numbers_are_jumpers no)
		(fp_line
			(start 2.504948 -1.616456)
			(end 2.504948 1.633728)
			(stroke
				(width 0.1524)
				(type default)
			)
			(layer "F.SilkS")
		)
		(fp_line
			(start 1.6002 -1.616456)
			(end 2.504948 -1.616456)
			(stroke
				(width 0.1524)
				(type default)
			)
			(layer "F.SilkS")
		)
		(fp_line
			(start -1.6002 -1.616456)
			(end -2.563114 -1.616456)
			(stroke
				(width 0.1524)
				(type default)
			)
			(layer "F.SilkS")
		)
		(fp_line
			(start -2.563114 -1.616456)
			(end -2.563114 1.633728)
			(stroke
				(width 0.1524)
				(type default)
			)
			(layer "F.SilkS")
		)
		(fp_line
			(start 2.504948 1.633728)
			(end 1.6002 1.633728)
			(stroke
				(width 0.1524)
				(type default)
			)
			(layer "F.SilkS")
		)
		(fp_line
			(start -2.563114 1.633728)
			(end -1.6002 1.633728)
			(stroke
				(width 0.1524)
				(type default)
			)
			(layer "F.SilkS")
		)
		(fp_line
			(start 2.286 7.366)
			(end 2.286 1.63195)
			(stroke
				(width 0.1524)
				(type default)
			)
			(layer "F.SilkS")
		)
		(fp_line
			(start 2.286 7.366)
			(end 1.600708 7.366)
			(stroke
				(width 0.1524)
				(type default)
			)
			(layer "F.SilkS")
		)
		(fp_line
			(start -2.286 7.366)
			(end -2.286 1.632712)
			(stroke
				(width 0.1524)
				(type default)
			)
			(layer "F.SilkS")
		)
		(fp_line
			(start -2.286 7.366)
			(end -1.60147 7.366)
			(stroke
				(width 0.1524)
				(type default)
			)
			(layer "F.SilkS")
		)
		(fp_rect
			(start -2.286 7.366)
			(end 2.286 -0.254)
			(stroke
				(width 0)
				(type default)
			)
			(fill no)
			(layer "F.CrtYd")
		)
		(fp_line
			(start 2.286 -0.254)
			(end 2.286 7.366)
			(stroke
				(width 0.1)
				(type default)
			)
			(layer "F.Fab")
		)
		(fp_line
			(start -2.286 -0.254)
			(end 2.286 -0.254)
			(stroke
				(width 0.1)
				(type default)
			)
			(layer "F.Fab")
		)
		(fp_line
			(start 2.286 7.366)
			(end -2.286 7.366)
			(stroke
				(width 0.1)
				(type default)
			)
			(layer "F.Fab")
		)
		(fp_line
			(start -2.286 7.366)
			(end -2.286 -0.254)
			(stroke
				(width 0.1)
				(type default)
			)
			(layer "F.Fab")
		)
		(pad "1" smd rect
			(at 0 0 90)
			(size 2.54 3.048)
			(layers "F.Cu" "F.Mask" "F.Paste")
			(net "PVCCMCP_CPU1")
		)
		(pad "2" smd rect
			(at 0 7.112 90)
			(size 2.54 3.048)
			(layers "F.Cu" "F.Mask" "F.Paste")
			(net "GND")
		)
	)
)
